FILE_TYPE = CONNECTIVITY;
{Allegro Design Entry HDL 17.2-2016 S081 (4005846) 1/11/2022}
"PAGE_NUMBER" = 74;
0"NC";
1"PVCCFA_EHV_CPU0\g";
2"PVCCIN_CPU0\g";
3"PVCCIN_CPU0\g";
4"PVNN_MAIN_CPU0\g";
5"PVCCIN_CPU0\g";
6"PVCCIN_CPU0\g";
7"PVCCIN_CPU0\g";
8"PVCCINFAON_CPU0\g";
9"PVCCIN_CPU0\g";
10"PVCCIN_CPU0\g";
11"PVCCIN_CPU0\g";
12"PVCCD_HV_CPU0\g";
13"PVCCIN_CPU0\g";
14"PVCCFA_EHV_FIVRA_CPU0\g";
15"GND\g";
16"GND\g";
17"GND\g";
18"GND\g";
19"GND\g";
20"GND\g";
21"GND\g";
22"GND\g";
23"GND\g";
24"GND\g";
25"GND\g";
26"GND\g";
27"GND\g";
28"GND\g";
%"Q_CAP"
"1","(-4250,-1650)","0","pure_quanta","I1";
;
PART_NUMBER"CH622KMEB01"
MATERIAL"X6S"
PACK_TYPE"C0402"
VALUE"22UF"
TOLERANCE"20%"
VOLTAGE"4V"
$LOCATION"C400"
CDS_LIB"pure_quanta"
CDS_LOCATION"C400"
$SEC"1"
CDS_SEC"1";
"B"
$PN"2"26;
"A"
$PN"1"14;
%"Q_CAP"
"1","(-1100,-1650)","0","pure_quanta","I10";
;
PART_NUMBER"CH622KMEB01"
MATERIAL"X6S"
PACK_TYPE"C0402"
VALUE"22UF"
TOLERANCE"20%"
VOLTAGE"4V"
$LOCATION"C413"
CDS_LIB"pure_quanta"
CDS_LOCATION"C413"
$SEC"1"
CDS_SEC"1";
"B"
$PN"2"26;
"A"
$PN"1"14;
%"Q_CAP"
"1","(1475,-850)","0","pure_quanta","I100";
;
PART_NUMBER"CH622KMEB01"
MATERIAL"X6S"
PACK_TYPE"C0402"
TOLERANCE"20%"
VOLTAGE"4V"
VALUE"22UF"
$LOCATION"C420"
CDS_LIB"pure_quanta"
CDS_LOCATION"C420"
$SEC"1"
CDS_SEC"1";
"B"
$PN"2"25;
"A"
$PN"1"1;
%"UNIVERSAL_GND"
"1","(1025,-425)","0","logical_power","I101";
;
CDS_LIB"logical_power"
HDL_POWER"GND";
"A"19;
%"Q_CAP"
"1","(1025,-150)","0","pure_quanta","I102";
;
PART_NUMBER"CH622KMEB01"
PACK_TYPE"C0402"
VOLTAGE"4V"
MATERIAL"X6S"
TOLERANCE"20%"
VALUE"22UF"
$LOCATION"C590"
CDS_LIB"pure_quanta"
CDS_LOCATION"C590"
$SEC"1"
CDS_SEC"1";
"B"
$PN"2"19;
"A"
$PN"1"4;
%"Q_CAP"
"1","(1925,-850)","0","pure_quanta","I103";
;
PART_NUMBER"CH622KMEB01"
PACK_TYPE"C0402"
MATERIAL"X6S"
TOLERANCE"20%"
VOLTAGE"4V"
VALUE"22UF"
$LOCATION"C421"
CDS_LIB"pure_quanta"
CDS_LOCATION"C421"
$SEC"1"
CDS_SEC"1";
"B"
$PN"2"25;
"A"
$PN"1"1;
%"UNIVERSAL_POWER"
"1","(1025,125)","0","logical_power","I104";
;
HDL_POWER"PVNN_MAIN_CPU0"
CDS_LIB"logical_power";
"A"4;
%"Q_CAP"
"1","(1175,725)","0","pure_quanta","I105";
;
PART_NUMBER"CH622KMEB01"
PACK_TYPE"C0402"
VOLTAGE"4V"
MATERIAL"X6S"
VALUE"22UF"
TOLERANCE"20%"
$LOCATION"C1017"
CDS_LIB"pure_quanta"
CDS_LOCATION"C1017"
$SEC"1"
CDS_SEC"1";
"B"
$PN"2"18;
"A"
$PN"1"7;
%"Q_CAP"
"1","(1625,725)","0","pure_quanta","I106";
;
PART_NUMBER"CH622KMEB01"
PACK_TYPE"C0402"
MATERIAL"X6S"
TOLERANCE"20%"
VALUE"22UF"
VOLTAGE"4V"
$LOCATION"C1021"
CDS_LIB"pure_quanta"
CDS_LOCATION"C1021"
$SEC"1"
CDS_SEC"1";
"B"
$PN"2"18;
"A"
$PN"1"7;
%"Q_CAP"
"1","(2375,-850)","0","pure_quanta","I107";
;
PART_NUMBER"CH622KMEB01"
PACK_TYPE"C0402"
MATERIAL"X6S"
TOLERANCE"20%"
VOLTAGE"4V"
VALUE"22UF"
$LOCATION"C422"
CDS_LIB"pure_quanta"
CDS_LOCATION"C422"
$SEC"1"
CDS_SEC"1";
"B"
$PN"2"25;
"A"
$PN"1"1;
%"Q_CAP"
"1","(2075,725)","0","pure_quanta","I108";
;
PART_NUMBER"CH622KMEB01"
PACK_TYPE"C0402"
VOLTAGE"4V"
VALUE"22UF"
TOLERANCE"20%"
MATERIAL"X6S"
$LOCATION"C1025"
CDS_LIB"pure_quanta"
CDS_LOCATION"C1025"
$SEC"1"
CDS_SEC"1";
"B"
$PN"2"18;
"A"
$PN"1"7;
%"Q_CAP"
"1","(2525,725)","0","pure_quanta","I109";
;
PART_NUMBER"CH622KMEB01"
PACK_TYPE"C0402"
TOLERANCE"20%"
MATERIAL"X6S"
VOLTAGE"4V"
VALUE"22UF"
$LOCATION"C1029"
CDS_LIB"pure_quanta"
CDS_LOCATION"C1029"
$SEC"1"
CDS_SEC"1";
"B"
$PN"2"18;
"A"
$PN"1"7;
%"Q_CAP"
"1","(-4250,-850)","0","pure_quanta","I11";
;
PART_NUMBER"CH622KMEB01"
TOLERANCE"20%"
PACK_TYPE"C0402"
VOLTAGE"4V"
MATERIAL"X6S"
VALUE"22UF"
$LOCATION"C399"
CDS_LIB"pure_quanta"
CDS_LOCATION"C399"
$SEC"1"
CDS_SEC"1";
"B"
$PN"2"28;
"A"
$PN"1"12;
%"Q_CAP"
"1","(2975,725)","0","pure_quanta","I110";
;
PART_NUMBER"CH622KMEB01"
PACK_TYPE"C0402"
TOLERANCE"20%"
VALUE"22UF"
VOLTAGE"4V"
MATERIAL"X6S"
$LOCATION"C1033"
CDS_LIB"pure_quanta"
CDS_LOCATION"C1033"
$SEC"1"
CDS_SEC"1";
"B"
$PN"2"18;
"A"
$PN"1"7;
%"Q_CAP"
"1","(1175,1500)","0","pure_quanta","I111";
;
PART_NUMBER"CH622KMEB01"
MATERIAL"X6S"
PACK_TYPE"C0402"
VOLTAGE"4V"
VALUE"22UF"
TOLERANCE"20%"
$LOCATION"C1016"
CDS_LIB"pure_quanta"
CDS_LOCATION"C1016"
$SEC"1"
CDS_SEC"1";
"B"
$PN"2"16;
"A"
$PN"1"6;
%"Q_CAP"
"1","(1625,1500)","0","pure_quanta","I112";
;
PART_NUMBER"CH622KMEB01"
PACK_TYPE"C0402"
MATERIAL"X6S"
VALUE"22UF"
VOLTAGE"4V"
TOLERANCE"20%"
$LOCATION"C1020"
CDS_LIB"pure_quanta"
CDS_LOCATION"C1020"
$SEC"1"
CDS_SEC"1";
"B"
$PN"2"16;
"A"
$PN"1"6;
%"Q_CAP"
"1","(1150,2250)","0","pure_quanta","I113";
;
PART_NUMBER"CH622KMEB01"
PACK_TYPE"C0402"
VALUE"22UF"
MATERIAL"X6S"
VOLTAGE"4V"
TOLERANCE"20%"
$LOCATION"C1015"
CDS_LIB"pure_quanta"
CDS_LOCATION"C1015"
$SEC"1"
CDS_SEC"1";
"B"
$PN"2"15;
"A"
$PN"1"5;
%"Q_CAP"
"1","(1150,3025)","0","pure_quanta","I114";
;
PART_NUMBER"CH622KMEB01"
PACK_TYPE"C0402"
MATERIAL"X6S"
VOLTAGE"4V"
VALUE"22UF"
TOLERANCE"20%"
$LOCATION"C1014"
CDS_LIB"pure_quanta"
CDS_LOCATION"C1014"
$SEC"1"
CDS_SEC"1";
"B"
$PN"2"17;
"A"
$PN"1"3;
%"Q_CAP"
"1","(1600,2250)","0","pure_quanta","I115";
;
PART_NUMBER"CH622KMEB01"
PACK_TYPE"C0402"
VALUE"22UF"
MATERIAL"X6S"
VOLTAGE"4V"
TOLERANCE"20%"
$LOCATION"C1019"
CDS_LIB"pure_quanta"
CDS_LOCATION"C1019"
$SEC"1"
CDS_SEC"1";
"B"
$PN"2"15;
"A"
$PN"1"5;
%"Q_CAP"
"1","(1600,3025)","0","pure_quanta","I116";
;
PART_NUMBER"CH622KMEB01"
PACK_TYPE"C0402"
MATERIAL"X6S"
VOLTAGE"4V"
TOLERANCE"20%"
VALUE"22UF"
$LOCATION"C1018"
CDS_LIB"pure_quanta"
CDS_LOCATION"C1018"
$SEC"1"
CDS_SEC"1";
"B"
$PN"2"17;
"A"
$PN"1"3;
%"Q_CAP"
"1","(2075,1500)","0","pure_quanta","I117";
;
PART_NUMBER"CH622KMEB01"
PACK_TYPE"C0402"
MATERIAL"X6S"
VOLTAGE"4V"
VALUE"22UF"
TOLERANCE"20%"
$LOCATION"C1024"
CDS_LIB"pure_quanta"
CDS_LOCATION"C1024"
$SEC"1"
CDS_SEC"1";
"B"
$PN"2"16;
"A"
$PN"1"6;
%"Q_CAP"
"1","(2525,1500)","0","pure_quanta","I118";
;
PART_NUMBER"CH622KMEB01"
MATERIAL"X6S"
PACK_TYPE"C0402"
TOLERANCE"20%"
VALUE"22UF"
VOLTAGE"4V"
$LOCATION"C1028"
CDS_LIB"pure_quanta"
CDS_LOCATION"C1028"
$SEC"1"
CDS_SEC"1";
"B"
$PN"2"16;
"A"
$PN"1"6;
%"Q_CAP"
"1","(2975,1500)","0","pure_quanta","I119";
;
PART_NUMBER"CH622KMEB01"
MATERIAL"X6S"
PACK_TYPE"C0402"
TOLERANCE"20%"
VALUE"22UF"
VOLTAGE"4V"
$LOCATION"C1032"
CDS_LIB"pure_quanta"
CDS_LOCATION"C1032"
$SEC"1"
CDS_SEC"1";
"B"
$PN"2"16;
"A"
$PN"1"6;
%"UNIVERSAL_POWER"
"1","(-4250,-575)","0","logical_power","I12";
;
HDL_POWER"PVCCD_HV_CPU0"
CDS_LIB"logical_power";
"A"12;
%"Q_CAP"
"1","(2050,2250)","0","pure_quanta","I120";
;
PART_NUMBER"CH622KMEB01"
MATERIAL"X6S"
PACK_TYPE"C0402"
VALUE"22UF"
TOLERANCE"20%"
VOLTAGE"4V"
$LOCATION"C1023"
CDS_LIB"pure_quanta"
CDS_LOCATION"C1023"
$SEC"1"
CDS_SEC"1";
"B"
$PN"2"15;
"A"
$PN"1"5;
%"Q_CAP"
"1","(2500,2250)","0","pure_quanta","I121";
;
PART_NUMBER"CH622KMEB01"
VALUE"22UF"
PACK_TYPE"C0402"
MATERIAL"X6S"
VOLTAGE"4V"
TOLERANCE"20%"
$LOCATION"C1027"
CDS_LIB"pure_quanta"
CDS_LOCATION"C1027"
$SEC"1"
CDS_SEC"1";
"B"
$PN"2"15;
"A"
$PN"1"5;
%"Q_CAP"
"1","(2050,3025)","0","pure_quanta","I122";
;
PART_NUMBER"CH622KMEB01"
MATERIAL"X6S"
PACK_TYPE"C0402"
TOLERANCE"20%"
VOLTAGE"4V"
VALUE"22UF"
$LOCATION"C1022"
CDS_LIB"pure_quanta"
CDS_LOCATION"C1022"
$SEC"1"
CDS_SEC"1";
"B"
$PN"2"17;
"A"
$PN"1"3;
%"Q_CAP"
"1","(2500,3025)","0","pure_quanta","I123";
;
PART_NUMBER"CH622KMEB01"
MATERIAL"X6S"
PACK_TYPE"C0402"
TOLERANCE"20%"
VALUE"22UF"
VOLTAGE"4V"
$LOCATION"C1026"
CDS_LIB"pure_quanta"
CDS_LOCATION"C1026"
$SEC"1"
CDS_SEC"1";
"B"
$PN"2"17;
"A"
$PN"1"3;
%"Q_CAP"
"1","(2950,2250)","0","pure_quanta","I124";
;
PART_NUMBER"CH622KMEB01"
VALUE"22UF"
PACK_TYPE"C0402"
MATERIAL"X6S"
VOLTAGE"4V"
TOLERANCE"20%"
$LOCATION"C1031"
CDS_LIB"pure_quanta"
CDS_LOCATION"C1031"
$SEC"1"
CDS_SEC"1";
"B"
$PN"2"15;
"A"
$PN"1"5;
%"Q_CAP"
"1","(2950,3025)","0","pure_quanta","I125";
;
PART_NUMBER"CH622KMEB01"
PACK_TYPE"C0402"
MATERIAL"X6S"
VALUE"22UF"
TOLERANCE"20%"
VOLTAGE"4V"
$LOCATION"C1030"
CDS_LIB"pure_quanta"
CDS_LOCATION"C1030"
$SEC"1"
CDS_SEC"1";
"B"
$PN"2"17;
"A"
$PN"1"3;
%"UNIVERSAL_POWER"
"1","(250,3300)","0","logical_power","I126";
;
HDL_POWER"PVCCIN_CPU0"
CDS_LIB"logical_power";
"A"3;
%"Q_CAP"
"1","(3425,725)","0","pure_quanta","I127";
;
PART_NUMBER"CH622KMEB01"
PACK_TYPE"C0402"
TOLERANCE"20%"
MATERIAL"X6S"
VALUE"22UF"
VOLTAGE"4V"
$LOCATION"C1037"
CDS_LIB"pure_quanta"
CDS_LOCATION"C1037"
$SEC"1"
CDS_SEC"1";
"B"
$PN"2"18;
"A"
$PN"1"7;
%"Q_CAP"
"1","(3875,725)","0","pure_quanta","I128";
;
PART_NUMBER"CH622KMEB01"
PACK_TYPE"C0402"
VALUE"22UF"
VOLTAGE"4V"
MATERIAL"X6S"
TOLERANCE"20%"
$LOCATION"C1041"
CDS_LIB"pure_quanta"
CDS_LOCATION"C1041"
$SEC"1"
CDS_SEC"1";
"B"
$PN"2"18;
"A"
$PN"1"7;
%"UNIVERSAL_GND"
"1","(4325,375)","0","logical_power","I129";
;
CDS_LIB"logical_power"
HDL_POWER"GND";
"A"18;
%"Q_CAP"
"1","(-4250,-50)","0","pure_quanta","I13";
;
PART_NUMBER"CH647KMEA04"
MATERIAL"X6S"
PACK_TYPE"C0805"
VOLTAGE"4V"
TOLERANCE"20%"
VALUE"47UF"
$LOCATION"C101"
CDS_LIB"pure_quanta"
$LOCATION"C101"
CDS_LOCATION"C101"
$SEC"1"
CDS_SEC"1";
"B"
$PN"2"24;
"A"
$PN"1"11;
%"Q_CAP"
"1","(4325,725)","0","pure_quanta","I130";
;
PART_NUMBER"CH622KMEB01"
PACK_TYPE"C0402"
VOLTAGE"4V"
VALUE"22UF"
MATERIAL"X6S"
TOLERANCE"20%"
$LOCATION"C1045"
CDS_LIB"pure_quanta"
CDS_LOCATION"C1045"
$SEC"1"
CDS_SEC"1";
"B"
$PN"2"18;
"A"
$PN"1"7;
%"Q_CAP"
"1","(3425,1500)","0","pure_quanta","I131";
;
PART_NUMBER"CH622KMEB01"
MATERIAL"X6S"
PACK_TYPE"C0402"
TOLERANCE"20%"
VALUE"22UF"
VOLTAGE"4V"
$LOCATION"C1036"
CDS_LIB"pure_quanta"
CDS_LOCATION"C1036"
$SEC"1"
CDS_SEC"1";
"B"
$PN"2"16;
"A"
$PN"1"6;
%"Q_CAP"
"1","(3875,1500)","0","pure_quanta","I132";
;
PART_NUMBER"CH622KMEB01"
MATERIAL"X6S"
PACK_TYPE"C0402"
VOLTAGE"4V"
VALUE"22UF"
TOLERANCE"20%"
$LOCATION"C1040"
CDS_LIB"pure_quanta"
CDS_LOCATION"C1040"
$SEC"1"
CDS_SEC"1";
"B"
$PN"2"16;
"A"
$PN"1"6;
%"Q_CAP"
"1","(3400,2250)","0","pure_quanta","I133";
;
PART_NUMBER"CH622KMEB01"
PACK_TYPE"C0402"
MATERIAL"X6S"
VALUE"22UF"
VOLTAGE"4V"
TOLERANCE"20%"
$LOCATION"C1035"
CDS_LIB"pure_quanta"
CDS_LOCATION"C1035"
$SEC"1"
CDS_SEC"1";
"B"
$PN"2"15;
"A"
$PN"1"5;
%"Q_CAP"
"1","(3400,3025)","0","pure_quanta","I134";
;
PART_NUMBER"CH622KMEB01"
MATERIAL"X6S"
PACK_TYPE"C0402"
VALUE"22UF"
VOLTAGE"4V"
TOLERANCE"20%"
$LOCATION"C1034"
CDS_LIB"pure_quanta"
CDS_LOCATION"C1034"
$SEC"1"
CDS_SEC"1";
"B"
$PN"2"17;
"A"
$PN"1"3;
%"Q_CAP"
"1","(3850,2250)","0","pure_quanta","I135";
;
PART_NUMBER"CH622KMEB01"
MATERIAL"X6S"
PACK_TYPE"C0402"
VALUE"22UF"
TOLERANCE"20%"
VOLTAGE"4V"
$LOCATION"C1039"
CDS_LIB"pure_quanta"
CDS_LOCATION"C1039"
$SEC"1"
CDS_SEC"1";
"B"
$PN"2"15;
"A"
$PN"1"5;
%"UNIVERSAL_GND"
"1","(3850,2675)","0","logical_power","I136";
;
CDS_LIB"logical_power"
HDL_POWER"GND";
"A"17;
%"Q_CAP"
"1","(3850,3025)","0","pure_quanta","I137";
;
PART_NUMBER"CH622KMEB01"
PACK_TYPE"C0402"
MATERIAL"X6S"
TOLERANCE"20%"
VALUE"22UF"
VOLTAGE"4V"
$LOCATION"C1038"
CDS_LIB"pure_quanta"
CDS_LOCATION"C1038"
$SEC"1"
CDS_SEC"1";
"B"
$PN"2"17;
"A"
$PN"1"3;
%"UNIVERSAL_GND"
"1","(4325,1150)","0","logical_power","I138";
;
CDS_LIB"logical_power"
HDL_POWER"GND";
"A"16;
%"Q_CAP"
"1","(4325,1500)","0","pure_quanta","I139";
;
PART_NUMBER"CH622KMEB01"
PACK_TYPE"C0402"
MATERIAL"X6S"
VOLTAGE"4V"
VALUE"22UF"
TOLERANCE"20%"
$LOCATION"C1044"
CDS_LIB"pure_quanta"
CDS_LOCATION"C1044"
$SEC"1"
CDS_SEC"1";
"B"
$PN"2"16;
"A"
$PN"1"6;
%"UNIVERSAL_POWER"
"1","(-4250,225)","0","logical_power","I14";
;
HDL_POWER"PVCCIN_CPU0"
CDS_LIB"logical_power";
"A"11;
%"UNIVERSAL_GND"
"1","(4300,1900)","0","logical_power","I140";
;
CDS_LIB"logical_power"
HDL_POWER"GND";
"A"15;
%"Q_CAP"
"1","(4300,2250)","0","pure_quanta","I141";
;
PART_NUMBER"CH622KMEB01"
VALUE"22UF"
MATERIAL"X6S"
PACK_TYPE"C0402"
TOLERANCE"20%"
VOLTAGE"4V"
$LOCATION"C1043"
CDS_LIB"pure_quanta"
CDS_LOCATION"C1043"
$SEC"1"
CDS_SEC"1";
"B"
$PN"2"15;
"A"
$PN"1"5;
%"Q_CAP"
"1","(-2000,-850)","0","pure_quanta","I142";
;
PART_NUMBER"CH622KMEB01"
MATERIAL"X6S"
PACK_TYPE"C0402"
VOLTAGE"4V"
VALUE"22UF"
TOLERANCE"20%"
$LOCATION"C408"
CDS_LIB"pure_quanta"
CDS_LOCATION"C408"
$SEC"1"
CDS_SEC"1";
"B"
$PN"2"27;
"A"
$PN"1"8;
%"Q_CAP"
"1","(-4250,725)","0","pure_quanta","I15";
;
PART_NUMBER"CH6101MEB03"
VALUE"10UF"
PACK_TYPE"C0402"
MATERIAL"X6S"
VOLTAGE"6.3V"
TOLERANCE"20%"
$LOCATION"C969"
CDS_LIB"pure_quanta"
CDS_LOCATION"C969"
$SEC"1"
CDS_SEC"1";
"B"
$PN"2"23;
"A"
$PN"1"2;
%"UNIVERSAL_POWER"
"1","(-4250,1000)","0","logical_power","I16";
;
HDL_POWER"PVCCIN_CPU0"
CDS_LIB"logical_power";
"A"2;
%"Q_CAP"
"1","(-3800,-850)","0","pure_quanta","I17";
;
PART_NUMBER"CH622KMEB01"
PACK_TYPE"C0402"
VOLTAGE"4V"
VALUE"22UF"
MATERIAL"X6S"
TOLERANCE"20%"
$LOCATION"C401"
CDS_LIB"pure_quanta"
CDS_LOCATION"C401"
$SEC"1"
CDS_SEC"1";
"B"
$PN"2"28;
"A"
$PN"1"12;
%"Q_CAP"
"1","(-3800,-50)","0","pure_quanta","I18";
;
PART_NUMBER"CH647KMEA04"
MATERIAL"X6S"
PACK_TYPE"C0805"
VOLTAGE"4V"
TOLERANCE"20%"
VALUE"47UF"
$LOCATION"C212"
CDS_LIB"pure_quanta"
$LOCATION"C212"
CDS_LOCATION"C212"
$SEC"1"
CDS_SEC"1";
"B"
$PN"2"24;
"A"
$PN"1"11;
%"Q_CAP"
"1","(-3350,-850)","0","pure_quanta","I19";
;
PART_NUMBER"CH622KMEB01"
VALUE"22UF"
VOLTAGE"4V"
MATERIAL"X6S"
TOLERANCE"20%"
PACK_TYPE"C0402"
$LOCATION"C403"
CDS_LIB"pure_quanta"
CDS_LOCATION"C403"
$SEC"1"
CDS_SEC"1";
"B"
$PN"2"28;
"A"
$PN"1"12;
%"UNIVERSAL_POWER"
"1","(-4250,-1375)","0","logical_power","I2";
;
HDL_POWER"PVCCFA_EHV_FIVRA_CPU0"
CDS_LIB"logical_power";
"A"14;
%"Q_CAP"
"1","(-3350,-50)","0","pure_quanta","I20";
;
PART_NUMBER"CH647KMEA04"
MATERIAL"X6S"
PACK_TYPE"C0805"
VOLTAGE"4V"
TOLERANCE"20%"
VALUE"47UF"
$LOCATION"C213"
CDS_LIB"pure_quanta"
$LOCATION"C213"
CDS_LOCATION"C213"
$SEC"1"
CDS_SEC"1";
"B"
$PN"2"24;
"A"
$PN"1"11;
%"Q_CAP"
"1","(-3800,725)","0","pure_quanta","I21";
;
PART_NUMBER"CH6101MEB03"
VALUE"10UF"
PACK_TYPE"C0402"
MATERIAL"X6S"
VOLTAGE"6.3V"
TOLERANCE"20%"
$LOCATION"C973"
CDS_LIB"pure_quanta"
CDS_LOCATION"C973"
$SEC"1"
CDS_SEC"1";
"B"
$PN"2"23;
"A"
$PN"1"2;
%"Q_CAP"
"1","(-3350,725)","0","pure_quanta","I22";
;
PART_NUMBER"CH6101MEB03"
VALUE"10UF"
PACK_TYPE"C0402"
MATERIAL"X6S"
VOLTAGE"6.3V"
TOLERANCE"20%"
$LOCATION"C977"
CDS_LIB"pure_quanta"
CDS_LOCATION"C977"
$SEC"1"
CDS_SEC"1";
"B"
$PN"2"23;
"A"
$PN"1"2;
%"Q_CAP"
"1","(-4250,1500)","0","pure_quanta","I23";
;
PART_NUMBER"CH6101MEB03"
MATERIAL"X6S"
TOLERANCE"20%"
VALUE"10UF"
VOLTAGE"6.3V"
PACK_TYPE"C0402"
$LOCATION"C968"
CDS_LIB"pure_quanta"
CDS_LOCATION"C968"
$SEC"1"
CDS_SEC"1";
"B"
$PN"2"22;
"A"
$PN"1"10;
%"UNIVERSAL_POWER"
"1","(-4250,1775)","0","logical_power","I24";
;
HDL_POWER"PVCCIN_CPU0"
CDS_LIB"logical_power";
"A"10;
%"Q_CAP"
"1","(-4275,2250)","0","pure_quanta","I25";
;
PART_NUMBER"CH6101MEB03"
PACK_TYPE"C0402"
MATERIAL"X6S"
TOLERANCE"20%"
VALUE"10UF"
VOLTAGE"6.3V"
$LOCATION"C967"
CDS_LIB"pure_quanta"
CDS_LOCATION"C967"
$SEC"1"
CDS_SEC"1";
"B"
$PN"2"21;
"A"
$PN"1"9;
%"UNIVERSAL_POWER"
"1","(-4275,2525)","0","logical_power","I26";
;
HDL_POWER"PVCCIN_CPU0"
CDS_LIB"logical_power";
"A"9;
%"Q_CAP"
"1","(-4275,3025)","0","pure_quanta","I27";
;
PART_NUMBER"CH6101MEB03"
PACK_TYPE"C0402"
MATERIAL"X6S"
TOLERANCE"20%"
VALUE"10UF"
VOLTAGE"6.3V"
$LOCATION"C966"
CDS_LIB"pure_quanta"
CDS_LOCATION"C966"
$SEC"1"
CDS_SEC"1";
"B"
$PN"2"20;
"A"
$PN"1"13;
%"Q_CAP"
"1","(-3800,1500)","0","pure_quanta","I28";
;
PART_NUMBER"CH6101MEB03"
MATERIAL"X6S"
PACK_TYPE"C0402"
TOLERANCE"20%"
VALUE"10UF"
VOLTAGE"6.3V"
$LOCATION"C972"
CDS_LIB"pure_quanta"
CDS_LOCATION"C972"
$SEC"1"
CDS_SEC"1";
"B"
$PN"2"22;
"A"
$PN"1"10;
%"Q_CAP"
"1","(-3350,1500)","0","pure_quanta","I29";
;
PART_NUMBER"CH6101MEB03"
MATERIAL"X6S"
TOLERANCE"20%"
VALUE"10UF"
VOLTAGE"6.3V"
PACK_TYPE"C0402"
$LOCATION"C976"
CDS_LIB"pure_quanta"
CDS_LOCATION"C976"
$SEC"1"
CDS_SEC"1";
"B"
$PN"2"22;
"A"
$PN"1"10;
%"Q_CAP"
"1","(-3800,-1650)","0","pure_quanta","I3";
;
PART_NUMBER"CH622KMEB01"
PACK_TYPE"C0402"
MATERIAL"X6S"
VALUE"22UF"
TOLERANCE"20%"
VOLTAGE"4V"
$LOCATION"C402"
CDS_LIB"pure_quanta"
CDS_LOCATION"C402"
$SEC"1"
CDS_SEC"1";
"B"
$PN"2"26;
"A"
$PN"1"14;
%"Q_CAP"
"1","(-3825,2250)","0","pure_quanta","I30";
;
PART_NUMBER"CH6101MEB03"
PACK_TYPE"C0402"
MATERIAL"X6S"
TOLERANCE"20%"
VALUE"10UF"
VOLTAGE"6.3V"
$LOCATION"C971"
CDS_LIB"pure_quanta"
CDS_LOCATION"C971"
$SEC"1"
CDS_SEC"1";
"B"
$PN"2"21;
"A"
$PN"1"9;
%"Q_CAP"
"1","(-3825,3025)","0","pure_quanta","I31";
;
PART_NUMBER"CH6101MEB03"
PACK_TYPE"C0402"
MATERIAL"X6S"
TOLERANCE"20%"
VALUE"10UF"
VOLTAGE"6.3V"
$LOCATION"C970"
CDS_LIB"pure_quanta"
CDS_LOCATION"C970"
$SEC"1"
CDS_SEC"1";
"B"
$PN"2"20;
"A"
$PN"1"13;
%"Q_CAP"
"1","(-3375,2250)","0","pure_quanta","I32";
;
PART_NUMBER"CH6101MEB03"
PACK_TYPE"C0402"
MATERIAL"X6S"
TOLERANCE"20%"
VALUE"10UF"
VOLTAGE"6.3V"
$LOCATION"C975"
CDS_LIB"pure_quanta"
CDS_LOCATION"C975"
$SEC"1"
CDS_SEC"1";
"B"
$PN"2"21;
"A"
$PN"1"9;
%"Q_CAP"
"1","(-3375,3025)","0","pure_quanta","I33";
;
PART_NUMBER"CH6101MEB03"
PACK_TYPE"C0402"
MATERIAL"X6S"
TOLERANCE"20%"
VALUE"10UF"
VOLTAGE"6.3V"
$LOCATION"C974"
CDS_LIB"pure_quanta"
CDS_LOCATION"C974"
$SEC"1"
CDS_SEC"1";
"B"
$PN"2"20;
"A"
$PN"1"13;
%"Q_CAP"
"1","(-2900,-850)","0","pure_quanta","I34";
;
PART_NUMBER"CH622KMEB01"
PACK_TYPE"C0402"
VOLTAGE"4V"
VALUE"22UF"
MATERIAL"X6S"
TOLERANCE"20%"
$LOCATION"C405"
CDS_LIB"pure_quanta"
CDS_LOCATION"C405"
$SEC"1"
CDS_SEC"1";
"B"
$PN"2"28;
"A"
$PN"1"12;
%"Q_CAP"
"1","(-2900,-50)","0","pure_quanta","I35";
;
PART_NUMBER"CH647KMEA04"
MATERIAL"X6S"
PACK_TYPE"C0805"
VOLTAGE"4V"
TOLERANCE"20%"
VALUE"47UF"
$LOCATION"C214"
CDS_LIB"pure_quanta"
$LOCATION"C214"
CDS_LOCATION"C214"
$SEC"1"
CDS_SEC"1";
"B"
$PN"2"24;
"A"
$PN"1"11;
%"Q_CAP"
"1","(-2450,-50)","0","pure_quanta","I36";
;
PART_NUMBER"CH647KMEA04"
MATERIAL"X6S"
PACK_TYPE"C0805"
TOLERANCE"20%"
VOLTAGE"4V"
VALUE"47UF"
$LOCATION"C215"
CDS_LIB"pure_quanta"
$LOCATION"C215"
CDS_LOCATION"C215"
$SEC"1"
CDS_SEC"1";
"B"
$PN"2"24;
"A"
$PN"1"11;
%"Q_CAP"
"1","(-2900,725)","0","pure_quanta","I37";
;
PART_NUMBER"CH6101MEB03"
VOLTAGE"6.3V"
VALUE"10UF"
PACK_TYPE"C0402"
TOLERANCE"20%"
MATERIAL"X6S"
$LOCATION"C981"
CDS_LIB"pure_quanta"
CDS_LOCATION"C981"
$SEC"1"
CDS_SEC"1";
"B"
$PN"2"23;
"A"
$PN"1"2;
%"Q_CAP"
"1","(-2450,725)","0","pure_quanta","I38";
;
PART_NUMBER"CH6101MEB03"
VOLTAGE"6.3V"
VALUE"10UF"
TOLERANCE"20%"
PACK_TYPE"C0402"
MATERIAL"X6S"
$LOCATION"C985"
CDS_LIB"pure_quanta"
CDS_LOCATION"C985"
$SEC"1"
CDS_SEC"1";
"B"
$PN"2"23;
"A"
$PN"1"2;
%"UNIVERSAL_POWER"
"1","(-2000,-575)","0","logical_power","I39";
;
HDL_POWER"PVCCINFAON_CPU0"
CDS_LIB"logical_power";
"A"8;
%"Q_CAP"
"1","(-3350,-1650)","0","pure_quanta","I4";
;
PART_NUMBER"CH622KMEB01"
PACK_TYPE"C0402"
VALUE"22UF"
MATERIAL"X6S"
VOLTAGE"4V"
TOLERANCE"20%"
$LOCATION"C404"
CDS_LIB"pure_quanta"
CDS_LOCATION"C404"
$SEC"1"
CDS_SEC"1";
"B"
$PN"2"26;
"A"
$PN"1"14;
%"Q_CAP"
"1","(-2000,-50)","0","pure_quanta","I40";
;
PART_NUMBER"CH647KMEA04"
MATERIAL"X6S"
VOLTAGE"4V"
TOLERANCE"20%"
VALUE"47UF"
PACK_TYPE"C0805"
$LOCATION"C216"
CDS_LIB"pure_quanta"
$LOCATION"C216"
CDS_LOCATION"C216"
$SEC"1"
CDS_SEC"1";
"B"
$PN"2"24;
"A"
$PN"1"11;
%"Q_CAP"
"1","(-1550,-850)","0","pure_quanta","I41";
;
PART_NUMBER"CH622KMEB01"
PACK_TYPE"C0402"
MATERIAL"X6S"
TOLERANCE"20%"
VOLTAGE"4V"
VALUE"22UF"
$LOCATION"C410"
CDS_LIB"pure_quanta"
CDS_LOCATION"C410"
$SEC"1"
CDS_SEC"1";
"B"
$PN"2"27;
"A"
$PN"1"8;
%"Q_CAP"
"1","(-1100,-850)","0","pure_quanta","I42";
;
PART_NUMBER"CH622KMEB01"
PACK_TYPE"C0402"
MATERIAL"X6S"
VOLTAGE"4V"
TOLERANCE"20%"
VALUE"22UF"
$LOCATION"C412"
CDS_LIB"pure_quanta"
CDS_LOCATION"C412"
$SEC"1"
CDS_SEC"1";
"B"
$PN"2"27;
"A"
$PN"1"8;
%"Q_CAP"
"1","(-1550,-50)","0","pure_quanta","I43";
;
PART_NUMBER"CH647KMEA04"
MATERIAL"X6S"
PACK_TYPE"C0805"
VOLTAGE"4V"
TOLERANCE"20%"
VALUE"47UF"
$LOCATION"C217"
CDS_LIB"pure_quanta"
$LOCATION"C217"
CDS_LOCATION"C217"
$SEC"1"
CDS_SEC"1";
"B"
$PN"2"24;
"A"
$PN"1"11;
%"Q_CAP"
"1","(-1100,-50)","0","pure_quanta","I44";
;
PART_NUMBER"CH647KMEA04"
MATERIAL"X6S"
PACK_TYPE"C0805"
VOLTAGE"4V"
TOLERANCE"20%"
VALUE"47UF"
$LOCATION"C218"
CDS_LIB"pure_quanta"
$LOCATION"C218"
CDS_LOCATION"C218"
$SEC"1"
CDS_SEC"1";
"B"
$PN"2"24;
"A"
$PN"1"11;
%"Q_CAP"
"1","(-2000,725)","0","pure_quanta","I45";
;
PART_NUMBER"CH6101MEB03"
VALUE"10UF"
PACK_TYPE"C0402"
MATERIAL"X6S"
TOLERANCE"20%"
VOLTAGE"6.3V"
$LOCATION"C989"
CDS_LIB"pure_quanta"
CDS_LOCATION"C989"
$SEC"1"
CDS_SEC"1";
"B"
$PN"2"23;
"A"
$PN"1"2;
%"Q_CAP"
"1","(-1550,725)","0","pure_quanta","I46";
;
PART_NUMBER"CH6101MEB03"
VOLTAGE"6.3V"
VALUE"10UF"
PACK_TYPE"C0402"
MATERIAL"X6S"
TOLERANCE"20%"
$LOCATION"C993"
CDS_LIB"pure_quanta"
CDS_LOCATION"C993"
$SEC"1"
CDS_SEC"1";
"B"
$PN"2"23;
"A"
$PN"1"2;
%"Q_CAP"
"1","(-1100,725)","0","pure_quanta","I47";
;
PART_NUMBER"CH6101MEB03"
VOLTAGE"6.3V"
VALUE"10UF"
TOLERANCE"20%"
MATERIAL"X6S"
PACK_TYPE"C0402"
$LOCATION"C997"
CDS_LIB"pure_quanta"
CDS_LOCATION"C997"
$SEC"1"
CDS_SEC"1";
"B"
$PN"2"23;
"A"
$PN"1"2;
%"Q_CAP"
"1","(-2900,1500)","0","pure_quanta","I48";
;
PART_NUMBER"CH6101MEB03"
PACK_TYPE"C0402"
TOLERANCE"20%"
VALUE"10UF"
VOLTAGE"6.3V"
MATERIAL"X6S"
$LOCATION"C980"
CDS_LIB"pure_quanta"
CDS_LOCATION"C980"
$SEC"1"
CDS_SEC"1";
"B"
$PN"2"22;
"A"
$PN"1"10;
%"Q_CAP"
"1","(-2450,1500)","0","pure_quanta","I49";
;
PART_NUMBER"CH6101MEB03"
PACK_TYPE"C0402"
TOLERANCE"20%"
VALUE"10UF"
VOLTAGE"6.3V"
MATERIAL"X6S"
$LOCATION"C984"
CDS_LIB"pure_quanta"
CDS_LOCATION"C984"
$SEC"1"
CDS_SEC"1";
"B"
$PN"2"22;
"A"
$PN"1"10;
%"Q_CAP"
"1","(-2900,-1650)","0","pure_quanta","I5";
;
PART_NUMBER"CH622KMEB01"
VALUE"22UF"
PACK_TYPE"C0402"
MATERIAL"X6S"
VOLTAGE"4V"
TOLERANCE"20%"
$LOCATION"C406"
CDS_LIB"pure_quanta"
CDS_LOCATION"C406"
$SEC"1"
CDS_SEC"1";
"B"
$PN"2"26;
"A"
$PN"1"14;
%"Q_CAP"
"1","(-2925,2250)","0","pure_quanta","I50";
;
PART_NUMBER"CH6101MEB03"
PACK_TYPE"C0402"
MATERIAL"X6S"
TOLERANCE"20%"
VALUE"10UF"
VOLTAGE"6.3V"
$LOCATION"C979"
CDS_LIB"pure_quanta"
CDS_LOCATION"C979"
$SEC"1"
CDS_SEC"1";
"B"
$PN"2"21;
"A"
$PN"1"9;
%"Q_CAP"
"1","(-2925,3025)","0","pure_quanta","I51";
;
PART_NUMBER"CH6101MEB03"
PACK_TYPE"C0402"
TOLERANCE"20%"
MATERIAL"X6S"
VALUE"10UF"
VOLTAGE"6.3V"
$LOCATION"C978"
CDS_LIB"pure_quanta"
CDS_LOCATION"C978"
$SEC"1"
CDS_SEC"1";
"B"
$PN"2"20;
"A"
$PN"1"13;
%"Q_CAP"
"1","(-2475,2250)","0","pure_quanta","I52";
;
PART_NUMBER"CH6101MEB03"
PACK_TYPE"C0402"
MATERIAL"X6S"
TOLERANCE"20%"
VALUE"10UF"
VOLTAGE"6.3V"
$LOCATION"C983"
CDS_LIB"pure_quanta"
CDS_LOCATION"C983"
$SEC"1"
CDS_SEC"1";
"B"
$PN"2"21;
"A"
$PN"1"9;
%"Q_CAP"
"1","(-2475,3025)","0","pure_quanta","I53";
;
PART_NUMBER"CH6101MEB03"
PACK_TYPE"C0402"
TOLERANCE"20%"
MATERIAL"X6S"
VALUE"10UF"
VOLTAGE"6.3V"
$LOCATION"C982"
CDS_LIB"pure_quanta"
CDS_LOCATION"C982"
$SEC"1"
CDS_SEC"1";
"B"
$PN"2"20;
"A"
$PN"1"13;
%"Q_CAP"
"1","(-2000,1500)","0","pure_quanta","I54";
;
PART_NUMBER"CH6101MEB03"
PACK_TYPE"C0402"
TOLERANCE"20%"
VALUE"10UF"
VOLTAGE"6.3V"
MATERIAL"X6S"
$LOCATION"C988"
CDS_LIB"pure_quanta"
CDS_LOCATION"C988"
$SEC"1"
CDS_SEC"1";
"B"
$PN"2"22;
"A"
$PN"1"10;
%"Q_CAP"
"1","(-1550,1500)","0","pure_quanta","I55";
;
PART_NUMBER"CH6101MEB03"
VALUE"10UF"
PACK_TYPE"C0402"
MATERIAL"X6S"
TOLERANCE"20%"
VOLTAGE"6.3V"
$LOCATION"C992"
CDS_LIB"pure_quanta"
CDS_LOCATION"C992"
$SEC"1"
CDS_SEC"1";
"B"
$PN"2"22;
"A"
$PN"1"10;
%"Q_CAP"
"1","(-1100,1500)","0","pure_quanta","I56";
;
PART_NUMBER"CH6101MEB03"
PACK_TYPE"C0402"
TOLERANCE"20%"
VALUE"10UF"
MATERIAL"X6S"
VOLTAGE"6.3V"
$LOCATION"C996"
CDS_LIB"pure_quanta"
CDS_LOCATION"C996"
$SEC"1"
CDS_SEC"1";
"B"
$PN"2"22;
"A"
$PN"1"10;
%"Q_CAP"
"1","(-2025,2250)","0","pure_quanta","I57";
;
PART_NUMBER"CH6101MEB03"
MATERIAL"X6S"
PACK_TYPE"C0402"
TOLERANCE"20%"
VALUE"10UF"
VOLTAGE"6.3V"
$LOCATION"C987"
CDS_LIB"pure_quanta"
CDS_LOCATION"C987"
$SEC"1"
CDS_SEC"1";
"B"
$PN"2"21;
"A"
$PN"1"9;
%"Q_CAP"
"1","(-2025,3025)","0","pure_quanta","I58";
;
PART_NUMBER"CH6101MEB03"
PACK_TYPE"C0402"
TOLERANCE"20%"
MATERIAL"X6S"
VALUE"10UF"
VOLTAGE"6.3V"
$LOCATION"C986"
CDS_LIB"pure_quanta"
CDS_LOCATION"C986"
$SEC"1"
CDS_SEC"1";
"B"
$PN"2"20;
"A"
$PN"1"13;
%"Q_CAP"
"1","(-1575,2250)","0","pure_quanta","I59";
;
PART_NUMBER"CH6101MEB03"
PACK_TYPE"C0402"
VALUE"10UF"
VOLTAGE"6.3V"
TOLERANCE"20%"
MATERIAL"X6S"
$LOCATION"C991"
CDS_LIB"pure_quanta"
CDS_LOCATION"C991"
$SEC"1"
CDS_SEC"1";
"B"
$PN"2"21;
"A"
$PN"1"9;
%"UNIVERSAL_GND"
"1","(-2900,-1175)","0","logical_power","I6";
;
CDS_LIB"logical_power"
HDL_POWER"GND";
"A"28;
%"Q_CAP"
"1","(-1575,3025)","0","pure_quanta","I60";
;
PART_NUMBER"CH6101MEB03"
PACK_TYPE"C0402"
TOLERANCE"20%"
MATERIAL"X6S"
VALUE"10UF"
VOLTAGE"6.3V"
$LOCATION"C990"
CDS_LIB"pure_quanta"
CDS_LOCATION"C990"
$SEC"1"
CDS_SEC"1";
"B"
$PN"2"20;
"A"
$PN"1"13;
%"Q_CAP"
"1","(-1125,2250)","0","pure_quanta","I61";
;
PART_NUMBER"CH6101MEB03"
MATERIAL"X6S"
PACK_TYPE"C0402"
TOLERANCE"20%"
VALUE"10UF"
VOLTAGE"6.3V"
$LOCATION"C995"
CDS_LIB"pure_quanta"
CDS_LOCATION"C995"
$SEC"1"
CDS_SEC"1";
"B"
$PN"2"21;
"A"
$PN"1"9;
%"Q_CAP"
"1","(-1125,3025)","0","pure_quanta","I62";
;
PART_NUMBER"CH6101MEB03"
PACK_TYPE"C0402"
TOLERANCE"20%"
MATERIAL"X6S"
VALUE"10UF"
VOLTAGE"6.3V"
$LOCATION"C994"
CDS_LIB"pure_quanta"
CDS_LOCATION"C994"
$SEC"1"
CDS_SEC"1";
"B"
$PN"2"20;
"A"
$PN"1"13;
%"UNIVERSAL_POWER"
"1","(-4275,3300)","0","logical_power","I63";
;
HDL_POWER"PVCCIN_CPU0"
CDS_LIB"logical_power";
"A"13;
%"Q_CAP"
"1","(-650,-1650)","0","pure_quanta","I64";
;
PART_NUMBER"CH622KMEB01"
VALUE"22UF"
PACK_TYPE"C0402"
MATERIAL"X6S"
VOLTAGE"4V"
TOLERANCE"20%"
$LOCATION"C415"
CDS_LIB"pure_quanta"
CDS_LOCATION"C415"
$SEC"1"
CDS_SEC"1";
"B"
$PN"2"26;
"A"
$PN"1"14;
%"Q_CAP"
"1","(-200,-1650)","0","pure_quanta","I65";
;
PART_NUMBER"CH622KMEB01"
VALUE"22UF"
PACK_TYPE"C0402"
MATERIAL"X6S"
VOLTAGE"4V"
TOLERANCE"20%"
$LOCATION"C417"
CDS_LIB"pure_quanta"
CDS_LOCATION"C417"
$SEC"1"
CDS_SEC"1";
"B"
$PN"2"26;
"A"
$PN"1"14;
%"UNIVERSAL_GND"
"1","(-200,-1200)","0","logical_power","I66";
;
CDS_LIB"logical_power"
HDL_POWER"GND";
"A"27;
%"UNIVERSAL_GND"
"1","(250,-2000)","0","logical_power","I67";
;
CDS_LIB"logical_power"
HDL_POWER"GND";
"A"26;
%"Q_CAP"
"1","(250,-1650)","0","pure_quanta","I68";
;
PART_NUMBER"CH622KMEB01"
MATERIAL"X6S"
PACK_TYPE"C0402"
VALUE"22UF"
TOLERANCE"20%"
VOLTAGE"4V"
$LOCATION"C418"
CDS_LIB"pure_quanta"
CDS_LOCATION"C418"
$SEC"1"
CDS_SEC"1";
"B"
$PN"2"26;
"A"
$PN"1"14;
%"UNIVERSAL_GND"
"1","(2375,-1175)","0","logical_power","I69";
;
CDS_LIB"logical_power"
HDL_POWER"GND";
"A"25;
%"Q_CAP"
"1","(-2450,-1650)","0","pure_quanta","I7";
;
PART_NUMBER"CH622KMEB01"
PACK_TYPE"C0402"
VALUE"22UF"
MATERIAL"X6S"
VOLTAGE"4V"
TOLERANCE"20%"
$LOCATION"C407"
CDS_LIB"pure_quanta"
CDS_LOCATION"C407"
$SEC"1"
CDS_SEC"1";
"B"
$PN"2"26;
"A"
$PN"1"14;
%"Q_CAP"
"1","(-650,-850)","0","pure_quanta","I70";
;
PART_NUMBER"CH622KMEB01"
PACK_TYPE"C0402"
MATERIAL"X6S"
VALUE"22UF"
VOLTAGE"4V"
TOLERANCE"20%"
$LOCATION"C414"
CDS_LIB"pure_quanta"
CDS_LOCATION"C414"
$SEC"1"
CDS_SEC"1";
"B"
$PN"2"27;
"A"
$PN"1"8;
%"Q_CAP"
"1","(-650,-50)","0","pure_quanta","I71";
;
PART_NUMBER"CH647KMEA04"
MATERIAL"X6S"
PACK_TYPE"C0805"
VOLTAGE"4V"
TOLERANCE"20%"
VALUE"47UF"
$LOCATION"C219"
CDS_LIB"pure_quanta"
$LOCATION"C219"
CDS_LOCATION"C219"
$SEC"1"
CDS_SEC"1";
"B"
$PN"2"24;
"A"
$PN"1"11;
%"Q_CAP"
"1","(-200,-850)","0","pure_quanta","I72";
;
PART_NUMBER"CH622KMEB01"
MATERIAL"X6S"
VOLTAGE"4V"
TOLERANCE"20%"
VALUE"22UF"
PACK_TYPE"C0402"
$LOCATION"C416"
CDS_LIB"pure_quanta"
CDS_LOCATION"C416"
$SEC"1"
CDS_SEC"1";
"B"
$PN"2"27;
"A"
$PN"1"8;
%"UNIVERSAL_GND"
"1","(-200,-400)","0","logical_power","I73";
;
CDS_LIB"logical_power"
HDL_POWER"GND";
"A"24;
%"Q_CAP"
"1","(-200,-50)","0","pure_quanta","I74";
;
PART_NUMBER"CH647KMEA04"
MATERIAL"X6S"
PACK_TYPE"C0805"
VOLTAGE"4V"
TOLERANCE"20%"
VALUE"47UF"
$LOCATION"C220"
CDS_LIB"pure_quanta"
$LOCATION"C220"
CDS_LOCATION"C220"
$SEC"1"
CDS_SEC"1";
"B"
$PN"2"24;
"A"
$PN"1"11;
%"Q_CAP"
"1","(-650,725)","0","pure_quanta","I75";
;
PART_NUMBER"CH6101MEB03"
VOLTAGE"6.3V"
VALUE"10UF"
PACK_TYPE"C0402"
MATERIAL"X6S"
TOLERANCE"20%"
$LOCATION"C1001"
CDS_LIB"pure_quanta"
CDS_LOCATION"C1001"
$SEC"1"
CDS_SEC"1";
"B"
$PN"2"23;
"A"
$PN"1"2;
%"UNIVERSAL_GND"
"1","(-200,375)","0","logical_power","I76";
;
CDS_LIB"logical_power"
HDL_POWER"GND";
"A"23;
%"Q_CAP"
"1","(-200,725)","0","pure_quanta","I77";
;
PART_NUMBER"CH6101MEB03"
VOLTAGE"6.3V"
VALUE"10UF"
PACK_TYPE"C0402"
MATERIAL"X6S"
TOLERANCE"20%"
$LOCATION"C1005"
CDS_LIB"pure_quanta"
CDS_LOCATION"C1005"
$SEC"1"
CDS_SEC"1";
"B"
$PN"2"23;
"A"
$PN"1"2;
%"Q_CAP"
"1","(275,725)","0","pure_quanta","I78";
;
PART_NUMBER"CH622KMEB01"
PACK_TYPE"C0402"
MATERIAL"X6S"
TOLERANCE"20%"
VOLTAGE"4V"
VALUE"22UF"
$LOCATION"C1009"
CDS_LIB"pure_quanta"
CDS_LOCATION"C1009"
$SEC"1"
CDS_SEC"1";
"B"
$PN"2"18;
"A"
$PN"1"7;
%"UNIVERSAL_POWER"
"1","(275,1000)","0","logical_power","I79";
;
HDL_POWER"PVCCIN_CPU0"
CDS_LIB"logical_power";
"A"7;
%"Q_CAP"
"1","(-2000,-1650)","0","pure_quanta","I8";
;
PART_NUMBER"CH622KMEB01"
PACK_TYPE"C0402"
MATERIAL"X6S"
VOLTAGE"4V"
TOLERANCE"20%"
VALUE"22UF"
$LOCATION"C409"
CDS_LIB"pure_quanta"
CDS_LOCATION"C409"
$SEC"1"
CDS_SEC"1";
"B"
$PN"2"26;
"A"
$PN"1"14;
%"Q_CAP"
"1","(725,725)","0","pure_quanta","I80";
;
PART_NUMBER"CH622KMEB01"
PACK_TYPE"C0402"
VALUE"22UF"
VOLTAGE"4V"
MATERIAL"X6S"
TOLERANCE"20%"
$LOCATION"C1013"
CDS_LIB"pure_quanta"
CDS_LOCATION"C1013"
$SEC"1"
CDS_SEC"1";
"B"
$PN"2"18;
"A"
$PN"1"7;
%"Q_CAP"
"1","(-650,1500)","0","pure_quanta","I81";
;
PART_NUMBER"CH6101MEB03"
VOLTAGE"6.3V"
MATERIAL"X6S"
PACK_TYPE"C0402"
TOLERANCE"20%"
VALUE"10UF"
$LOCATION"C1000"
CDS_LIB"pure_quanta"
CDS_LOCATION"C1000"
$SEC"1"
CDS_SEC"1";
"B"
$PN"2"22;
"A"
$PN"1"10;
%"UNIVERSAL_GND"
"1","(-200,1150)","0","logical_power","I82";
;
CDS_LIB"logical_power"
HDL_POWER"GND";
"A"22;
%"Q_CAP"
"1","(-200,1500)","0","pure_quanta","I83";
;
PART_NUMBER"CH6101MEB03"
PACK_TYPE"C0402"
VALUE"10UF"
MATERIAL"X6S"
TOLERANCE"20%"
VOLTAGE"6.3V"
$LOCATION"C1004"
CDS_LIB"pure_quanta"
CDS_LOCATION"C1004"
$SEC"1"
CDS_SEC"1";
"B"
$PN"2"22;
"A"
$PN"1"10;
%"UNIVERSAL_GND"
"1","(-225,1900)","0","logical_power","I84";
;
CDS_LIB"logical_power"
HDL_POWER"GND";
"A"21;
%"Q_CAP"
"1","(-675,2250)","0","pure_quanta","I85";
;
PART_NUMBER"CH6101MEB03"
MATERIAL"X6S"
PACK_TYPE"C0402"
TOLERANCE"20%"
VALUE"10UF"
VOLTAGE"6.3V"
$LOCATION"C999"
CDS_LIB"pure_quanta"
CDS_LOCATION"C999"
$SEC"1"
CDS_SEC"1";
"B"
$PN"2"21;
"A"
$PN"1"9;
%"Q_CAP"
"1","(-675,3025)","0","pure_quanta","I86";
;
PART_NUMBER"CH6101MEB03"
PACK_TYPE"C0402"
MATERIAL"X6S"
TOLERANCE"20%"
VALUE"10UF"
VOLTAGE"6.3V"
$LOCATION"C998"
CDS_LIB"pure_quanta"
CDS_LOCATION"C998"
$SEC"1"
CDS_SEC"1";
"B"
$PN"2"20;
"A"
$PN"1"13;
%"Q_CAP"
"1","(-225,2250)","0","pure_quanta","I87";
;
PART_NUMBER"CH6101MEB03"
PACK_TYPE"C0402"
MATERIAL"X6S"
TOLERANCE"20%"
VALUE"10UF"
VOLTAGE"6.3V"
$LOCATION"C1003"
CDS_LIB"pure_quanta"
CDS_LOCATION"C1003"
$SEC"1"
CDS_SEC"1";
"B"
$PN"2"21;
"A"
$PN"1"9;
%"UNIVERSAL_GND"
"1","(-225,2675)","0","logical_power","I88";
;
CDS_LIB"logical_power"
HDL_POWER"GND";
"A"20;
%"Q_CAP"
"1","(-225,3025)","0","pure_quanta","I89";
;
PART_NUMBER"CH6101MEB03"
PACK_TYPE"C0402"
MATERIAL"X6S"
TOLERANCE"20%"
VALUE"10UF"
VOLTAGE"6.3V"
$LOCATION"C1002"
CDS_LIB"pure_quanta"
CDS_LOCATION"C1002"
$SEC"1"
CDS_SEC"1";
"B"
$PN"2"20;
"A"
$PN"1"13;
%"Q_CAP"
"1","(-1550,-1650)","0","pure_quanta","I9";
;
PART_NUMBER"CH622KMEB01"
MATERIAL"X6S"
PACK_TYPE"C0402"
TOLERANCE"20%"
VOLTAGE"4V"
VALUE"22UF"
$LOCATION"C411"
CDS_LIB"pure_quanta"
CDS_LOCATION"C411"
$SEC"1"
CDS_SEC"1";
"B"
$PN"2"26;
"A"
$PN"1"14;
%"Q_CAP"
"1","(275,1500)","0","pure_quanta","I90";
;
PART_NUMBER"CH622KMEB01"
MATERIAL"X6S"
PACK_TYPE"C0402"
VOLTAGE"4V"
TOLERANCE"20%"
VALUE"22UF"
$LOCATION"C1008"
CDS_LIB"pure_quanta"
CDS_LOCATION"C1008"
$SEC"1"
CDS_SEC"1";
"B"
$PN"2"16;
"A"
$PN"1"6;
%"UNIVERSAL_POWER"
"1","(275,1775)","0","logical_power","I91";
;
HDL_POWER"PVCCIN_CPU0"
CDS_LIB"logical_power";
"A"6;
%"Q_CAP"
"1","(725,1500)","0","pure_quanta","I92";
;
PART_NUMBER"CH622KMEB01"
PACK_TYPE"C0402"
MATERIAL"X6S"
VOLTAGE"4V"
VALUE"22UF"
TOLERANCE"20%"
$LOCATION"C1012"
CDS_LIB"pure_quanta"
CDS_LOCATION"C1012"
$SEC"1"
CDS_SEC"1";
"B"
$PN"2"16;
"A"
$PN"1"6;
%"Q_CAP"
"1","(250,2250)","0","pure_quanta","I93";
;
PART_NUMBER"CH622KMEB01"
MATERIAL"X6S"
VALUE"22UF"
PACK_TYPE"C0402"
TOLERANCE"20%"
VOLTAGE"4V"
$LOCATION"C1007"
CDS_LIB"pure_quanta"
CDS_LOCATION"C1007"
$SEC"1"
CDS_SEC"1";
"B"
$PN"2"15;
"A"
$PN"1"5;
%"UNIVERSAL_POWER"
"1","(250,2525)","0","logical_power","I94";
;
HDL_POWER"PVCCIN_CPU0"
CDS_LIB"logical_power";
"A"5;
%"Q_CAP"
"1","(250,3025)","0","pure_quanta","I95";
;
PART_NUMBER"CH622KMEB01"
MATERIAL"X6S"
PACK_TYPE"C0402"
TOLERANCE"20%"
VALUE"22UF"
VOLTAGE"4V"
$LOCATION"C1006"
CDS_LIB"pure_quanta"
CDS_LOCATION"C1006"
$SEC"1"
CDS_SEC"1";
"B"
$PN"2"17;
"A"
$PN"1"3;
%"Q_CAP"
"1","(700,2250)","0","pure_quanta","I96";
;
PART_NUMBER"CH622KMEB01"
MATERIAL"X6S"
PACK_TYPE"C0402"
VALUE"22UF"
TOLERANCE"20%"
VOLTAGE"4V"
$LOCATION"C1011"
CDS_LIB"pure_quanta"
CDS_LOCATION"C1011"
$SEC"1"
CDS_SEC"1";
"B"
$PN"2"15;
"A"
$PN"1"5;
%"Q_CAP"
"1","(700,3025)","0","pure_quanta","I97";
;
PART_NUMBER"CH622KMEB01"
MATERIAL"X6S"
PACK_TYPE"C0402"
TOLERANCE"20%"
VALUE"22UF"
VOLTAGE"4V"
$LOCATION"C1010"
CDS_LIB"pure_quanta"
CDS_LOCATION"C1010"
$SEC"1"
CDS_SEC"1";
"B"
$PN"2"17;
"A"
$PN"1"3;
%"Q_CAP"
"1","(1025,-850)","0","pure_quanta","I98";
;
PART_NUMBER"CH622KMEB01"
PACK_TYPE"C0402"
MATERIAL"X6S"
TOLERANCE"20%"
VOLTAGE"4V"
VALUE"22UF"
$LOCATION"C419"
CDS_LIB"pure_quanta"
CDS_LOCATION"C419"
$SEC"1"
CDS_SEC"1";
"B"
$PN"2"25;
"A"
$PN"1"1;
%"UNIVERSAL_POWER"
"1","(1025,-575)","0","logical_power","I99";
;
HDL_POWER"PVCCFA_EHV_CPU0"
CDS_LIB"logical_power";
"A"1;
END.
